CONCISE PART LIST - 1  
10M04SAU324I7G-10M04SAU324I7G,A AJ10M040T03              1       
74CBTLV3126PW-74CBTLV3126PW,SMA AL003126K08              5       
74CBTLV3126PW-74CBTLV3126PW,SMB AL003126K08              1       
74HC1G126GW-74HC1G126GW,SMLF,IA AL1G0126007              1       
74LVC1G02GW_SMLF-74LVC1G02GW,IA ALVC1G02000              1       
74LVC1G07GV-74LVC1G07GV,SMLF,IA AL1G0007001              2       
74LVC1G126GW_SMLF-74LVC1G126GWA AL1G0126023              1       
9QXL2001BNHGI8-9QXL2001BNHGI8,A AJ020010003              1       
9SQ440NQQI8-9SQ440NQQI8,SMLF,IA AJ004400000              1       
ADM1086AKSZREEL7-ADM1086AKSZ-RA AL001086001              1       
ADS1015IDGSR-ADS1015IDGSR,SMLFA AL001015K00              1       
APX80929SAG7-APX809-29SAG-7,SMA AL080929000              1       
BAS70057F-BAS70-05-7-F,SMLF,ICA BC0BAS70Z01              1       
BAT547F-BAT547F,SMLF,IC,BC0BATA BC0BAT54Z53              1       
CONN10_10142708102011LF-CONN10A DFHD10MS383              2       
CONN10_G2100HT0038071-CONN10_GA DFHD10MS268              1       
CONN24_52SH90245BRD-CONN24_52SA DFHD24MS090              1       
CONN2_AAABAT029P15-CONN2_AAA-BA DFHS02FR031              1       
CONN3_210HP1030BR1-CONN3_210-HA DFHD03MS213              2       
CONN3_HFK1030G000LAF-CONN3_HFKA DFHD03MS239              2       
CONN56_ME2005602311011-CONN56_A DFHS56FR013              4       
CONN7_ABASAT054KA1-CONN7_ABA-SA DFHD07MS215              1       
CONN9_2UB3903013101F-CONN9_2UBA DFHS09FS026              1       
DELTA_L-DELTA-L,THLF,EMPTY,TP24 TP24                     24      
DIODE_TVS-SMF14A,SMLF,IC,BCSMFA BCSMF14AZ01              5       
DUMMY_SYMBOL-BARCODE,MECH,EMPTA DUMMY6                   2       
DUMMY_SYMBOL-BATTERY_SYMBOL,MEA DUMMY12                  1       
DUMMY_SYMBOL-EFI BIOS LABEL,MEA DUMMY28_HCLU2002010      1       
DUMMY_SYMBOL-MECHANIC_SYMBOL,MA DUMMY10                  1       
DUMMY_SYMBOL-PB-E1_SMALL,MECH,A DUMMY3                   1       
DUMMY_SYMBOL-PCBA_LABEL_15X5,MA DUMMY4                   1       
DUMMY_SYMBOL-PCB_VENDOR_LOGO_1A DUMMY7                   1       
DUMMY_SYMBOL-QUANTA_LOGO_7X26,A DUMMY1                   1       
DUMMY_SYMBOL-WEEE,MECH,EMPTY,DA DUMMY2                   1       
EMMITSBURG_REV0P9-GFNOCPU04302A AJ0QV2N0T00              1       
GTL2014PW-GTL2014PW,SMLF,IC,ALA AL002014K01              2       
HOLE_TH-EMPTY,DUMMY50 DUMMY50                  4       
HOLE_TH-EMPTY,HOLE491 HOLE491                  2       
HOLE_TH-EMPTY,HOLE1068 HOLE1068                 3       
HOLE_TH-EMPTY,HOLE1079 HOLE1079                 12      
HOLE_TH-EMPTY,HOLE1087 HOLE1087                 15      
HOLE_TH-EMPTY,HOLE1098 HOLE1098                 2       
HOLE_TH-EMPTY,HOLE1212 HOLE1212                 4       
HOLE_TH-EMPTY,HOLE1214 HOLE1214                 2       
HOLE_TH-EMPTY,HOLE1222 HOLE1222                 2       
HOLE_TH-EMPTY,TMP-Q_HOLE78 TMP-Q_HOLE78             2       
IDTQS3VH257QG_SMLF-IDTQS3VH257A AL000257W24              2       
ISL69260IRAZT-ISL69260IRAZ-T,SA AL069260000              4       
ISL99390FRZTR5935-ISL99390FRZ-A AL099390004              22      
ISL99390FRZTR5935-ISL99390FRZ-B AL099390004              2       
M24128BWDW6TP-M24128-BWDW6TP,SA AKE30Z0K610              1       
MAX11607EUAT-MAX11607EUA+T,SMLA AL011607000              1       
MAX9634FEUKT-MAX9634FEUK+T,SMLA AL009634002              2       
ME_DUMMY_SYMBOL-PICKUP_SMDC10,A DUMMY49                  4       
ME_DUMMY_SYMBOL-PICKUP_SMDC20,A DUMMY48                  10      
MOSFET_NCH_1D3S-PSMNR58-30YLH,A BAMNR580000              2       
MOSFET_NCH_DUAL-2N7002KDW,SMLFA BAM70020047              5       
MOSFET_N_GSD-NX7002AK,SMLF,IC,A BAM70020062              2       
MOSFET_N_SMLF-BSS138K,BSS138K,A BAM138K0000              6       
MOSFET_N_SMLF-BSS138K,BSS138K,B BAM138K0000              1       
MOSFET_PCH_GDS_ESD_PROTECTED-PA BAM34150008              1       
MP5981GLUZ-MP5981GLU-Z,SMLF,ICA AL005981000              2       
MPQ8626GDZ-MPQ8626GD-Z,SMLF,ICA AL008626000              2       
MPQ8633AGLEC807Z-MPQ8633AGLE-CA AL008633007              1       
MPQ8633AGLEC807Z-MPQ8633AGLE-CB AL008633007              1       
MPQ8633BGLEC838Z-MPQ8633BGLE-CA AL008633005              2       
NB695GDZ-NB695GD-Z,SMLF,IC,AL0A AL000695001              1       
NC7SB3157_SMLF-NC7SB3157P6X,NCA ALSB3157000              5       
NC7SZ66M5X_SMLF-NC7SZ66M5X,NC7A AL07SZ66004              1       
NCP3284MNTXG-NCP3284MNTXG,SMLFA AL003284001              1       
OSC4_SIT1602AI2233E50000000D-5A BF650000037              1       
PCA9306DCTR-PCA9306DCTR,SMLF,IA AL009306C00              1       
PCA9546APWR-PCA9546APWR,SMLF,IA AL09546AK01              3       
PCA9548APW-PCA9548APW,SMLF,IC,A AL009548K00              1       
PCA9555PW_SMLF-PCA9555PW,IC,TMA TMP_QAL009555K04         3       
PCA9617ADP-PCA9617ADP,SMLF,IC,A AL009617K02              4       
PI6CV304LE-PI6CV304LE,SMLF,IC,A AL000304K01              1       
Q_CAPP_RDLLF-270UF,16V,20%,OSCA CC72703MD03              1       
Q_CAPP_SMLF-100UF,16V,20%,OSCOA CC71003MZ32              2       
Q_CAPP_SMLF-100UF,16V,20%,POSCA CH7103M8804              5       
Q_CAPP_SMLF-220UF,6.3V,20%,ALUA CC72201MZ28              1       
Q_CAPP_SMLF-330UF,2V,35%,SPCAPA CH733RY8807              6       
Q_CAPP_SMLF-470UF,2.5V,20%,EMPA CH747LM8818              14      
Q_CAPP_SMLF-470UF,2.5V,20%,SPCA CH747LM8818              4       
Q_CAPP_SMLF-470UF,2V,20%,EMPTYA CH747RM8822              1       
Q_CAPP_SMLF-470UF,2V,20%,POSCAA CH747RM8822              1       
Q_CAPP_THLF-270UF,16V,20%,OSCOA CC72703MD33              16      
Q_CAPP_THLF-560UF,2.5V,20%,EMPA CC7560JMD18              2       
Q_CAPP_THLF-560UF,2.5V,20%,OSCA CC7560JMD18              34      
Q_CAPP_THLF-560UF,6.3V,20%,EMPA CC75601MD18              1       
Q_CAPP_THLF-560UF,6.3V,20%,OSCA CC75601MD18              3       
Q_CAP_0402-0.01UF,25V,10%,X7R,A CH31004KB17              1       
Q_CAP_0402-0.022UF,16V,10%,EMPA CH32203KB11              1       
Q_CAP_0402-0.022UF,16V,10%,X7RA CH32203KB11              2       
Q_CAP_0402-0.1UF,25V,10%,EMPTYA CH4104K1B00              17      
Q_CAP_0402-0.1UF,25V,10%,X7R,CA CH4104K1B00              281     
Q_CAP_0402-0.22UF,16V,10%,EMPTA CH4223K1B00              1       
Q_CAP_0402-0.22UF,16V,10%,X7R,A CH4223K1B00              8       
Q_CAP_0402-1000PF,50V,5%,EMPTYA CH21006JB10              16      
Q_CAP_0402-1000PF,50V,5%,X7R,TA CH21006JB10              11      
Q_CAP_0402-100PF,50V,5%,EMPTY,A CH11006JB00              1       
Q_CAP_0402-100PF,50V,5%,NPO,CHA CH11006JB00              1       
Q_CAP_0402-100PF,50V,5%,X7R,CHA CH11006JB18              2       
Q_CAP_0402-10PF,50V,1%,NPO,TMPA CH0106F0B00              1       
Q_CAP_0402-15PF,50V,5%,C0G,CH0A CH01506JB06              2       
Q_CAP_0402-1NF,50V,10%,X7R,CH2A CH21006KB16              2       
Q_CAP_0402-1UF,6.3V,10%,EMPTY,A CH5101K1B01              6       
Q_CAP_0402-27PF  ,50V ,5% ,EMPA CH02706JB06              2       
Q_CAP_0402-27PF  ,50V ,5% ,NPOA CH02706JB06              2       
Q_CAP_0402-3300PF,50V,10%,EMPTA CH2336K1B12              2       
Q_CAP_0402-3300PF,50V,10%,X7R,A CH2336K1B12              43      
Q_CAP_0402-4.7UF,6.3V,20%,X6S,A CH5471MEB01              6       
Q_CAP_0402-470PF,50V,10%,X7R,TA CH14706KB18              8       
Q_CAP_0402-47PF,50V,5%,NPO,TMPA CH04706JB01              1       
Q_CAP_0402-680PF,50V,10%,X7R,TA CH16806KB17              2       
Q_CAP_0805-22UF,4V,20%,EMPTY,TA CH622KMEA01              7       
Q_CAP_0805-22UF,4V,20%,X6S,TMPA CH622KMEA01              76      
Q_CAP_0805-47UF,4V,20%,X6S,CH6A CH647KMEA00              33      
Q_CAP_C0201-0.22UF,6.3V,10%,X6A CH4221KEE00              2       
Q_CAP_C0402-0.047UF,25V,10%,X7A CH3474K1B04              6       
Q_CAP_C0402-100NF,50V,10%,EMPTA CH4106K1B01              9       
Q_CAP_C0402-100NF,50V,10%,X7R,A CH4106K1B01              64      
Q_CAP_C0402-10UF,6.3V,20%,X6S,A CH6101MEB01              14      
Q_CAP_C0402-1UF,16V,10%,EMPTY,A CH5103KEB01              3       
Q_CAP_C0402-1UF,16V,10%,X6S,CHA CH5103KEB01              55      
Q_CAP_C0402-1UF,25V,10%,EMPTY,A CH5104KEB02              12      
Q_CAP_C0402-1UF,25V,10%,X6S,CHA CH5104KEB02              30      
Q_CAP_C0402-2.2UF,10V,10%,EMPTA CH5222KEB01              4       
Q_CAP_C0402-2.2UF,10V,10%,X6S,A CH5222KEB01              58      
Q_CAP_C0402-2.2UF,6.3V,20%,EMPA CH5221MEB00              1       
Q_CAP_C0402-2.2UF,6.3V,20%,X6SA CH5221MEB00              32      
Q_CAP_C0402-22UF,4V,20%,X6S,CHA CH622KMEB02              217     
Q_CAP_C0402-3900PF,50V,10%,X7RA CH23906KB14              1       
Q_CAP_C0402-470PF,50V,5%,NPO,CA CH1476J0B08              1       
Q_CAP_C0603-10UF,4V,20%,EMPTY,A CH610KME907              2       
Q_CAP_C0603-10UF,6.3V,20%,X6S,A CH6101ME900              15      
Q_CAP_C0603-2.2UF,16V,10%,X6S,A CH5223KE901              1       
Q_CAP_C0603-22UF,4V,20%,X6S,CHA CH622KME901              13      
Q_CAP_C0603-22UF,6.3V,20%,X6S,A CH6221ME900              7       
Q_CAP_C0603-4.7UF,16V,10%,X6S,A CH5473KE902              1       
Q_CAP_C0603-47UF,2.5V,20%,X6S,A CH647LME901              28      
Q_CAP_C0805-100UF,4V,20%,X6S,CA CH710KMEA00              156     
Q_CAP_C0805-10UF,16V,10%,EMPTYA CH6103KEA00              2       
Q_CAP_C0805-10UF,16V,10%,X6S,CA CH6103KEA00              6       
Q_CAP_C0805-10UF,16V,10%,X7R,CA CH6103K1A00              63      
Q_CAP_C0805-10UF,25V,10%,X6S,CA CH6104KEA00              16      
Q_CAP_C0805-22UF,10V,20%,X6S,CA CH6222MEA00              5       
Q_CAP_C0805-22UF,16V,20%,EMPTYA CH6223MEA00              9       
Q_CAP_C0805-22UF,16V,20%,X6S,CA CH6223MEA00              133     
Q_CAP_C0805-22UF,25V,20%,X5R,CA CH6224M9A00              1       
Q_CAP_DIFFBUS_C0201-DIFF BUS_0A CH4221MEE01              362     
Q_CAP_DIFFBUS_C0201-DIFF BUS_0B CH4101KEE02              2       
Q_CAP_DIFFBUS_C0402-DIFF BUS_0A CH4103K1B08              2       
Q_CAP_SATA6G_C0402-SATA6G_0.01A CH31004KB17              4       
Q_CRYSTAL_SMLF-32.768KHZ,IC,BGA BG632768012              1       
Q_INDUCTOR4P_12-67/320MA,320MAA CX21SN67000              3       
Q_INDUCTOR4P_14-150NH,SMLF,INDA CV+15^0TZ04              16      
Q_INDUCTOR_SMLF-1.5UH/53A,IND,A CV-15^0MZ02              1       
Q_INDUCTOR_SMLF-100NH/16A,IND,A CV+10G0MZ04              8       
Q_INDUCTOR_SMLF-120NH/76A,IND,A CV+12^0TZ06              2       
Q_INDUCTOR_SMLF-120NH/94A,IND,A CV+12^0KZ16              6       
Q_INDUCTOR_SMLF-130NH/106A,EMPA CV+13^0KZ11              2       
Q_INDUCTOR_SMLF-130NH/106A,INDA CV+13^0KZ11              6       
Q_INDUCTOR_SMLF-1UH,EMPTY,CV-1A CV-10B0MZ13              1       
Q_INDUCTOR_SMLF-1UH,IND,CV-10BA CV-10B0MZ13              4       
Q_INDUCTOR_SMLF-3.3UH/10A,IND,A CV-33A0MZ02              1       
Q_INDUCTOR_SMLF-300NH/33A,IND,A CV+30Y0KZ05              3       
Q_INDUCTOR_SMLF-50NH/148A,IND,A CVA50^0EZ01              2       
Q_INDUCTOR_SMLF-BLM15AG121SN1DA CX5AG121002              2       
Q_INDUCTOR_SMLF-BLM18PG121SN1DA CX8PG121009              3       
Q_INDUCTOR_SMLF-BLM18SG331TN1DA CX8SG331000              2       
Q_INDUCTOR_SMLF-BLM18SN220TN1DA CX220TN1001              2       
Q_INDUCTOR_SMLF-FCM2012KF-601TA CX601T05003              3       
Q_LED_SMLF-LED_GREEN,19-213/GVA BEGR0278Z00              1       
Q_LED_SMLF-LED_RED,19-217/R6C-A BERD0034Z07              1       
Q_OSC4P_SMLF-25MHZ,OSC,BF62500A BF625000014              1       
Q_RES_0402LF -9.53K,1%,1/16W ,A CS29532FB10              1       
Q_RES_0402LF-0,1%,1/16W,CHIP,TA CS00002FB00              2       
Q_RES_0402LF-0,5%,1/16W,CHIP,CA CS00002JB38              427     
Q_RES_0402LF-0,5%,1/16W,EMPTY,A CS00002JB38              67      
Q_RES_0402LF-1,1%,1/16W,CHIP,CA CS-1002FB23              7       
Q_RES_0402LF-1.33K,1%,1/16W,CHA CS21332FB05              4       
Q_RES_0402LF-1.5K,1%,1/16W,EMPA CS21502FB14              1       
Q_RES_0402LF-10,1%,1/16W,CHIP,A CS01002FB21              15      
Q_RES_0402LF-100,1%,1/16W,CHIPA CS11002FB22              69      
Q_RES_0402LF-100,1%,1/16W,CHIPB CS11002FB07              2       
Q_RES_0402LF-100,1%,1/16W,EMPTA CS11002FB22              23      
Q_RES_0402LF-100K,1%,1/16W,CHIA CS41002FB28              16      
Q_RES_0402LF-100K,1%,1/16W,EMPA CS41002FB09              8       
Q_RES_0402LF-100K,1%,1/16W,EMPB CS41002FB28              2       
Q_RES_0402LF-100K,5%,1/16W,CHIA CS41002JB20              2       
Q_RES_0402LF-10K,1%,1/16W,CHIPA CS31002FB26              185     
Q_RES_0402LF-10K,1%,1/16W,EMPTA CS31002FB26              62      
Q_RES_0402LF-10K,1%,1/16W,EMPTB CS31002FB08              8       
Q_RES_0402LF-10K,5%,1/16W,CHIPA CS31002JB28              17      
Q_RES_0402LF-10K,5%,1/16W,EMPTA CS31002JB28              9       
Q_RES_0402LF-11.8K,1%,1/16W,CHA CS31182FB18              1       
Q_RES_0402LF-113,1%,1/16W,CHIPA CS11132FB01              1       
Q_RES_0402LF-12.4K,1%,1/16W,CHA CS31242FB13              2       
Q_RES_0402LF-120,1%,1/16W,CHIPA CS11202FB11              1       
Q_RES_0402LF-120K,1%,1/16W,CHIA CS41202FB17              3       
Q_RES_0402LF-127K,1%,1/16W,CHIA CS41272FB19              4       
Q_RES_0402LF-12K,1%,1/16W,EMPTA CS31202FB15              1       
Q_RES_0402LF-15.4K,1%,1/16W,CHA CS31542FB14              4       
Q_RES_0402LF-150,1%,1/16W,CHIPA CS11502FB21              17      
Q_RES_0402LF-150,5%,1/16W,CHIPA CS11502JB22              1       
Q_RES_0402LF-150K,1%,1/16W,CHIA CS41502FB18              1       
Q_RES_0402LF-15K,1%,1/16W,CHIPA CS31502FB24              1       
Q_RES_0402LF-18.2K,0.1%,1/16W,A CS31822BB00              1       
Q_RES_0402LF-18.2K,0.1%,1/16W,B CS31822BB00              1       
Q_RES_0402LF-196K,1%,1/16W,CHIA CS41962FB01              4       
Q_RES_0402LF-1K,0.1%,1/16W,CHIA CS21002BB00              2       
Q_RES_0402LF-1K,1%,1/16W,CHIP,A CS21002FB24              116     
Q_RES_0402LF-1K,1%,1/16W,EMPTYA CS21002FB24              46      
Q_RES_0402LF-1K,5%,1/16W,CHIP,A CS21002JB34              18      
Q_RES_0402LF-1K,5%,1/16W,EMPTYA CS21002JB34              28      
Q_RES_0402LF-2.2,1%,1/16W,CHIPA CS-2202FB00              30      
Q_RES_0402LF-2.2,1%,1/16W,EMPTA CS-2202FB00              2       
Q_RES_0402LF-2.21K    ,1%  ,1/A CS22212FB11              1       
Q_RES_0402LF-2.2K ,5%,1/16W,CHA CS22202JB18              46      
Q_RES_0402LF-2.2K ,5%,1/16W,EMA CS22202JB18              10      
Q_RES_0402LF-2.49K,1%,1/16W,CHA CS22492FB22              1       
Q_RES_0402LF-2.4K,1%,1/16W,CHIA CS22402FB00              4       
Q_RES_0402LF-200,1%,1/16W,CHIPA CS12002FB25              7       
Q_RES_0402LF-200,1%,1/16W,EMPTA CS12002FB25              2       
Q_RES_0402LF-200K,1%,1/16W,CHIA CS42002FB12              1       
Q_RES_0402LF-20K,1%,1/16W,CHIPA CS32002FB29              3       
Q_RES_0402LF-20K,5%,1/16W,CHIPA CS32002JB12              3       
Q_RES_0402LF-20K,5%,1/16W,EMPTA CS32002JB12              1       
Q_RES_0402LF-21.5K,1%,1/16W,CHA CS32152FB17              1       
Q_RES_0402LF-22,1%,1/16W,CHIP,A CS02202FB12              7       
Q_RES_0402LF-23.2K,1%,1/16W,CHA CS32322FB11              4       
Q_RES_0402LF-240,1%,1/16W,CHIPA CS12402FB03              23      
Q_RES_0402LF-240,1%,1/16W,EMPTA CS12402FB03              44      
Q_RES_0402LF-249,1%,1/16W,CHIPA CS12492FB12              10      
Q_RES_0402LF-26.1K,1%,1/16W,CHA CS32612FB09              1       
Q_RES_0402LF-26.1K,1%,1/16W,EMA CS32612FB09              1       
Q_RES_0402LF-27.4,1%,1/16W,CHIA CS02742FB19              2       
Q_RES_0402LF-28K,1%,1/16W,EMPTA CS32802FB05              6       
Q_RES_0402LF-2K,1%,1/16W,CHIP,A CS22002FB19              53      
Q_RES_0402LF-2K,1%,1/16W,EMPTYA CS22002FB19              1       
Q_RES_0402LF-3.3,1%,1/16W,CHIPA CS-3302FB00              22      
Q_RES_0402LF-3.3,1%,1/16W,EMPTA CS-3302FB00              2       
Q_RES_0402LF-30.1K    ,1%  ,1/A CS33012FB18              1       
Q_RES_0402LF-301,1%,1/16W,CHIPA CS13012FB14              6       
Q_RES_0402LF-31.6K,1%,1/16W,CHA CS33162FB14              1       
Q_RES_0402LF-33,5%,1/16W,CHIP,A CS03302JB29              99      
Q_RES_0402LF-33.2,1%,1/16W,CHIA CS03322FB34              132     
Q_RES_0402LF-332,1%,1/16W,CHIPA CS13322FB10              1       
Q_RES_0402LF-33K    ,1%  ,1/16A CS33302FB14              1       
Q_RES_0402LF-35.7K,1%,1/16W,CHA CS33572FB13              4       
Q_RES_0402LF-36K,1%,1/16W,CHIPA CS33602FB15              1       
Q_RES_0402LF-36K,1%,1/16W,EMPTA CS33602FB15              1       
Q_RES_0402LF-4.32K,1%,1/16W,CHA CS24322FB14              2       
Q_RES_0402LF-4.64K,0.5%,1/16W,A CS24642DB00              1       
Q_RES_0402LF-4.7,1%,1/16W,CHIPA CS-4702FB19              8       
Q_RES_0402LF-4.75K,1%,1/16W,CHA CS24752FB12              9       
Q_RES_0402LF-4.75K,1%,1/16W,EMA CS24752FB12              4       
Q_RES_0402LF-4.7K,1%,1/16W,CHIA CS24702FB10              13      
Q_RES_0402LF-4.7K,1%,1/16W,EMPA CS24702FB10              12      
Q_RES_0402LF-4.7K,5%,1/16W,CHIA CS24702JB38              34      
Q_RES_0402LF-4.7K,5%,1/16W,EMPA CS24702JB38              22      
Q_RES_0402LF-412,1%,1/16W,CHIPA CS14122FB15              4       
Q_RES_0402LF-49.9     ,1%  ,1/A CS04992FB31              23      
Q_RES_0402LF-49.9     ,1%  ,1/B CS04992FB31              5       
Q_RES_0402LF-499,1%,1/16W,CHIPA CS14992FB24              6       
Q_RES_0402LF-5.1,5%,1/16W,CHIPA CS-5102JB03              1       
Q_RES_0402LF-5.11K,1%,1/16W,CHA CS25112FB15              1       
Q_RES_0402LF-5.23K,1%,1/16W,CHA CS25232FB18              1       
Q_RES_0402LF-510K,5%,1/16W,CHIA CS45102JB16              1       
Q_RES_0402LF-54.9K,1%,1/16W,CHA CS35492FB14              4       
Q_RES_0402LF-562,1%,1/16W,CHIPA CS15622FB01              1       
Q_RES_0402LF-576,1%,1/16W,CHIPA CS15762FB26              5       
Q_RES_0402LF-6.19K,1%,1/16W,CHA CS26192FB14              1       
Q_RES_0402LF-6.81K,1%,1/16W,CHA CS26812FB13              1       
Q_RES_0402LF-60.4,1%,1/16W,CHIA CS06042FB03              1       
Q_RES_0402LF-60.4K,1%,1/16W,CHA CS36042FB10              2       
Q_RES_0402LF-7.32K,1%,1/16W,CHA CS27322FB12              1       
Q_RES_0402LF-7.5K,1%,1/16W,CHIA CS27502FB11              1       
Q_RES_0402LF-75,1%,1/16W,CHIP,A CS07502FB17              5       
Q_RES_0402LF-75,1%,1/16W,EMPTYA CS07502FB17              1       
Q_RES_0402LF-750,1%,1/16W,CHIPA CS17502FB19              1       
Q_RES_0402LF-75K,1%,1/16W,CHIPA CS37502FB12              1       
Q_RES_0402LF-8.25K,1%,1/16W,CHA CS28252FB03              2       
Q_RES_0402LF-8.87K,1%,1/16W,EMA CS28872FB01              33      
Q_RES_0402LF-84.5K,1%,1/16W,CHA CS38452FB14              4       
Q_RES_0402LF-86.6K,1%,1/16W,CHA CS38662FB16              1       
Q_RES_0402LF-9.09K,1%,1/16W,CHA CS29092FB27              2       
Q_RES_0402LF-9.31K,1%,1/16W,CHA CS29312FB13              1       
Q_RES_0603LF-1,1%,1/10W,CHIP,CA CS-1003F920              3       
Q_RES_0603LF-10M,1%,1/10W,CHIPA CS61003F900              1       
Q_RES_0603LF-2.2,1%,1/10W,CHIPA CS-2203F902              2       
Q_RES_0603LF-200K,0.1%,1/10W,EA CS42003B901              1       
Q_RES_0805LF-0,5%,1/8W,CHIP,CSA CS00004JA40              1       
Q_RES_0805LF-0,5%,1/8W,EMPTY,CA CS00004JA40              1       
Q_RES_1206LF-0,,1/2W,CHIP,CS00A CS00007T200              2       
Q_RES_1206LF-0,,1/2W,EMPTY,CS0A CS00007T200              2       
Q_RES_1206LF-0,5%,1/4W,CHIP,CSA CS00006J248              2       
Q_RES_1206LF-0,5%,1/4W,EMPTY,CA CS00006J248              2       
Q_RES_4P_12-0.001,1%,3W,SMLF,CA CS+001DFR00              2       
Q_RES_R0402LF-887,1%,1/16W,CHIA CS18872FB01              1       
Q_SHORT_SM-EMPTY,SHORT6 SHORT6                   16      
Q_XTAL_4P_13BI_24GND-25MHZ,SMLA BG625000802              1       
Q_XTAL_4P_13_SMLF-25MHZ,IC,BG6A BG625000142              1       
RAA2213404GNPHB0-RAA2213404GNPA AL221340002              8       
RAA229126GNPHA0-RAA229126GNP#HA AL229126000              2       
RT9818C44GV-RT9818C-44GV,SMLF,A AL009818001              1       
SCHOTTKY_AC-SX34F,SMLF,IC,BC00A BC00SX34Z01              1       
SCONN140_G64V3431BHR-SCONN140_A DFHSE0FS038              2       
SCONN140_G64V3431BHR-SCONN140_B DFHSE0FS038              1       
SCONN168_623403212-SCONN168_6-A DFHSG8FS003              2       
SCONN280_ME1028040102011-SCONNA DFHST0FS008              1       
SCONN288_ADR50001P003C01-SCONNA DFHST8FS301              16      
SCONN288_ADR50001P013C01-SCONNA DFHST8FS302              16      
SCONN60_QSH03001LDAKTR-SCONN60A DFHS60FS001              1       
SCONN75K_APCI0155P004A-SCONN75A DFHS75FR313              1       
SCONN84_123318136-SCONN84_1-23A DFHS84FS009              6       
SLG55221120010VTR-SLG55221-120A AL055221001              1       
SN74LVC1G07DCKR-SN74LVC1G07DCKA AL1G0007016              1       
SN74LVC1G08DBVR_SMLF-SN74LVC1GA AL1G0008012              2       
SN74LVC1G17DCKR-SN74LVC1G17DCKA AL1G0017003              2       
SN74LVC2G07DCKR_SMLF-SN74LVC2GA AL002G07006              6       
SN74LVC2G17DCKR-SN74LVC2G17DCKA AL002G17001              2       
SOCKET4677_AZIFS054P001C01-SOCA DGA^7000016              2       
SW8S_DHNF04FTVTR-SW8S_DHNF04FTA DHP00004F00              2       
TDR_3P_TH2-EMPTY,N_A N_A                      12      
TMP75AIDR-TMP75AIDR,SMLF,IC,ALA AL000075061              2       
TPS2553DBVR1-TPS2553DBVR-1,SMLA AL002553002              1       
TPS259520DSGR-TPS259520DSGR,SMA AL259520000              5       
TPS259540DSGR-TPS259540DSGR,SMA AL259540000              5       
TPS259824ONRGER-TPS259824ONRGEA AL259824002              1       
TPS3897PDRYR-TPS3897PDRYR,SMLFA AL003897006              1       
TP_TDR_4P_FTS_TH-TP_TDR_4P_DIPA N_A                      24      
TP_TP-NA,TP30    TP30                     8       
TS3A24157RSER-TS3A24157RSER,SMA AL024157000              2       

Total                                     4358    
END CONCISE PART LIST
